(kicad_pcb
	(version 20221018)
	(generator pcbnew)
	(general
    (thickness 1.7403)
  )
	(paper "A4")
	(title_block
    (title "Data Center RDIMM DDR4 Tester")
    (date "2024-09-30")
    (rev "1.2.4")
		(comment 9 "footprints 159-165 of 690")
	)
	(layers
    (0 "F.Cu" signal)
    (1 "In1.Cu" power)
    (2 "In2.Cu" signal)
    (3 "In3.Cu" power)
    (4 "In4.Cu" power)
    (5 "In5.Cu" signal)
    (6 "In6.Cu" power)
    (7 "In7.Cu" signal)
    (8 "In8.Cu" power)
    (9 "In9.Cu" signal)
    (10 "In10.Cu" power)
    (31 "B.Cu" signal)
    (32 "B.Adhes" user "B.Adhesive")
    (33 "F.Adhes" user "F.Adhesive")
    (34 "B.Paste" user)
    (35 "F.Paste" user)
    (36 "B.SilkS" user "B.Silkscreen")
    (37 "F.SilkS" user "F.Silkscreen")
    (38 "B.Mask" user)
    (39 "F.Mask" user)
    (40 "Dwgs.User" user "User.Drawings")
    (41 "Cmts.User" user "User.Comments")
    (42 "Eco1.User" user "User.Eco1")
    (43 "Eco2.User" user "User.Eco2")
    (44 "Edge.Cuts" user)
    (45 "Margin" user)
    (46 "B.CrtYd" user "B.Courtyard")
    (47 "F.CrtYd" user "F.Courtyard")
    (48 "B.Fab" user)
    (49 "F.Fab" user)
  )
	(footprint "data-center-rdimm-ddr4-tester-footprints:SOT-723" (layer "F.Cu")
    (at 148.85 127.55 90)
    (property "Author" "Antmicro")
    (property "License" "Apache-2.0")
    (property "MPN" "TPD2E009DRTR")
    (property "Manufacturer" "Texas Instruments")
    (property "Sheetfile" "interfaces.kicad_sch")
    (property "Sheetname" "Interfaces")
    (property "ki_description" "2-Channel ESD Solution for High-Speed (6-Gbps) Differential Interface")
    (attr smd)
    (fp_text reference "D3" (at 1.385 -0.84 180) (layer "F.SilkS")
        (effects (font (size 0.7 0.7) (thickness 0.15)) (justify left bottom))
    )
    (fp_text value "TPD2E009_SOT-9X3" (at 0 1.7 90) (layer "F.Fab") hide
        (effects (font (size 0.7 0.7) (thickness 0.15)) (justify left bottom))
    )
    (fp_text user "${REFERENCE}" (at -0.83 4 90) (layer "F.Fab") hide
        (effects (font (size 0.7 0.7) (thickness 0.15)) (justify left bottom))
    )
    (fp_text user "License: Apache-2.0" (at -0.83 6.4 90) (layer "F.Fab") hide
        (effects (font (size 0.7 0.7) (thickness 0.15)) (justify left bottom))
    )
    (fp_text user "Author: Antmicro" (at -0.83 5.2 90) (layer "F.Fab") hide
        (effects (font (size 0.7 0.7) (thickness 0.15)) (justify left bottom))
    )
    (fp_line (start -0.43 -0.1375) (end -0.43 0.1375)
      (stroke (width 0.15) (type solid)) (layer "F.SilkS"))
    (fp_line (start 0.43 -0.63) (end -0.2175 -0.63)
      (stroke (width 0.15) (type solid)) (layer "F.SilkS"))
    (fp_line (start 0.43 -0.23) (end 0.43 -0.63)
      (stroke (width 0.15) (type solid)) (layer "F.SilkS"))
    (fp_line (start 0.43 0.23) (end 0.43 0.63)
      (stroke (width 0.15) (type solid)) (layer "F.SilkS"))
    (fp_line (start 0.43 0.63) (end -0.22 0.63)
      (stroke (width 0.15) (type solid)) (layer "F.SilkS"))
    (fp_rect (start -0.83 -0.83) (end 0.83 0.83)
      (stroke (width 0.05) (type solid)) (fill none) (layer "F.CrtYd"))
    (fp_line (start -0.09 -0.53) (end -0.43 -0.19)
      (stroke (width 0.15) (type solid)) (layer "F.Fab"))
    (fp_line (start 0.424 -0.528) (end 0.424 0.524)
      (stroke (width 0.15) (type solid)) (layer "F.Fab"))
    (fp_line (start 0.424 0.524) (end -0.424 0.524)
      (stroke (width 0.15) (type solid)) (layer "F.Fab"))
    (fp_rect (start 0.424 0.524) (end -0.43 -0.528)
      (stroke (width 0.15) (type solid)) (fill none) (layer "F.Fab"))
    (pad "1" smd rect (at -0.501 -0.401) (size 0.3 0.4) (layers "F.Cu" "F.Paste" "F.Mask")
      (net 11 "DBG_USB_N") (pinfunction "1") (pintype "passive"))
    (pad "2" smd rect (at -0.501 0.399) (size 0.3 0.4) (layers "F.Cu" "F.Paste" "F.Mask")
      (net 10 "DBG_USB_P") (pinfunction "2") (pintype "passive"))
    (pad "3" smd rect (at 0.499 -0.001) (size 0.3 0.4) (layers "F.Cu" "F.Paste" "F.Mask")
      (net 9 "GND") (pinfunction "3") (pintype "passive"))
  )
	(footprint "data-center-rdimm-ddr4-tester-footprints:C_0603_1608Metric" (layer "F.Cu")
    (at 125.686328 85.826674)
    (descr "Capacitor SMD 0603")
    (tags "capacitor 0603")
    (property "Author" "Antmicro")
    (property "Dielectric" "")
    (property "License" "Apache-2.0")
    (property "MPN" "06031C103JAT2A")
    (property "Manufacturer" "AVX")
    (property "Sheetfile" "supply.kicad_sch")
    (property "Sheetname" "Supply")
    (property "Val" "10n")
    (property "Voltage" "")
    (property "ki_description" " ")
    (attr smd)
    (fp_text reference "C113" (at -1.386328 -4.426674) (layer "F.SilkS")
        (effects (font (size 0.7 0.7) (thickness 0.15)) (justify left bottom))
    )
    (fp_text value "C_10n_0603" (at 0 1.6) (layer "F.Fab") hide
        (effects (font (size 0.7 0.7) (thickness 0.15)) (justify left bottom))
    )
    (fp_text user "Author: Antmicro" (at -1.682 4.894) (layer "F.Fab") hide
        (effects (font (size 0.7 0.7) (thickness 0.15)) (justify left bottom))
    )
    (fp_text user "License: Apache-2.0" (at -1.682 5.895) (layer "F.Fab") hide
        (effects (font (size 0.7 0.7) (thickness 0.15)) (justify left bottom))
    )
    (fp_text user "${REFERENCE}" (at -1.682 3.895) (layer "F.Fab") hide
        (effects (font (size 0.7 0.7) (thickness 0.15)) (justify left bottom))
    )
    (fp_line (start -0.3 -0.3) (end 0.3 -0.3)
      (stroke (width 0.15) (type solid)) (layer "F.SilkS"))
    (fp_line (start -0.3 0.3) (end 0.3 0.3)
      (stroke (width 0.15) (type solid)) (layer "F.SilkS"))
    (fp_rect (start -1.24 -0.7) (end 1.24 0.7)
      (stroke (width 0.05) (type solid)) (fill none) (layer "F.CrtYd"))
    (fp_rect (start -0.8 -0.4) (end 0.8 0.4)
      (stroke (width 0.15) (type solid)) (fill none) (layer "F.Fab"))
    (pad "1" smd roundrect (at -0.7 0) (size 0.6 0.8) (layers "F.Cu" "F.Paste" "F.Mask") (roundrect_rratio 0.2)
      (net 184 "VPP") (pintype "passive"))
    (pad "2" smd roundrect (at 0.7 0) (size 0.6 0.8) (layers "F.Cu" "F.Paste" "F.Mask") (roundrect_rratio 0.2)
      (net 9 "GND") (pintype "passive"))
  )
	(footprint "data-center-rdimm-ddr4-tester-footprints:KEMET_A" (layer "F.Cu")
    (at 168.07 93.97 90)
    (descr "Capacitor SMD KEMET_A")
    (tags "capacitor SMD KEMET_A")
    (property "Author" "Antmicro")
    (property "Dielectric" "")
    (property "License" "Apache-2.0")
    (property "MPN" "298D107X06R3A2T")
    (property "Manufacturer" "Vishay")
    (property "Sheetfile" "fpga-power.kicad_sch")
    (property "Sheetname" "FPGA power")
    (property "Val" "100u")
    (property "Voltage" "")
    (property "ki_description" " ")
    (attr smd)
    (fp_text reference "C20" (at 1.81 -0.38 90) (layer "F.SilkS")
        (effects (font (size 0.7 0.7) (thickness 0.15)) (justify left bottom))
    )
    (fp_text value "C_100u_KEMET_A" (at 0 2 90) (layer "F.Fab") hide
        (effects (font (size 0.7 0.7) (thickness 0.15)) (justify left bottom))
    )
    (fp_text user "License: Apache-2.0" (at -2.1 5.198 90) (layer "F.Fab") hide
        (effects (font (size 0.7 0.7) (thickness 0.15)) (justify left bottom))
    )
    (fp_text user "Author: Antmicro" (at -2.1 6.198 90) (layer "F.Fab") hide
        (effects (font (size 0.7 0.7) (thickness 0.15)) (justify left bottom))
    )
    (fp_text user "${REFERENCE}" (at -2.1 4.198 90) (layer "F.Fab") hide
        (effects (font (size 0.7 0.7) (thickness 0.15)) (justify left bottom))
    )
    (fp_line (start -1.925 -0.825) (end -1.625 -0.825)
      (stroke (width 0.12) (type solid)) (layer "F.SilkS"))
    (fp_line (start -1.775 -0.975) (end -1.775 -0.675)
      (stroke (width 0.12) (type solid)) (layer "F.SilkS"))
    (fp_line (start -1.5 -0.85) (end -1.2 -0.85)
      (stroke (width 0.12) (type solid)) (layer "F.SilkS"))
    (fp_line (start -1.5 -0.7) (end -1.5 -0.85)
      (stroke (width 0.12) (type solid)) (layer "F.SilkS"))
    (fp_line (start -1.5 0.7) (end -1.5 0.85)
      (stroke (width 0.12) (type solid)) (layer "F.SilkS"))
    (fp_line (start -1.5 0.85) (end -1.2 0.85)
      (stroke (width 0.12) (type solid)) (layer "F.SilkS"))
    (fp_line (start 1.5 -0.85) (end 1.2 -0.85)
      (stroke (width 0.12) (type solid)) (layer "F.SilkS"))
    (fp_line (start 1.5 -0.7) (end 1.5 -0.85)
      (stroke (width 0.12) (type solid)) (layer "F.SilkS"))
    (fp_line (start 1.5 0.7) (end 1.5 0.85)
      (stroke (width 0.12) (type solid)) (layer "F.SilkS"))
    (fp_line (start 1.5 0.85) (end 1.2 0.85)
      (stroke (width 0.12) (type solid)) (layer "F.SilkS"))
    (fp_rect (start -1.9 -1.05) (end 1.9 1.05)
      (stroke (width 0.05) (type solid)) (fill none) (layer "F.CrtYd"))
    (fp_rect (start -1.601 -0.802) (end 1.6 0.8)
      (stroke (width 0.1) (type solid)) (fill none) (layer "F.Fab"))
    (pad "1" smd rect (at -1.2 0 90) (size 1.2 1.2) (layers "F.Cu" "F.Paste" "F.Mask")
      (net 147 "1V0_SYS") (pintype "passive"))
    (pad "2" smd rect (at 1.2 0 90) (size 1.2 1.2) (layers "F.Cu" "F.Paste" "F.Mask")
      (net 9 "GND") (pintype "passive"))
  )
	(footprint "data-center-rdimm-ddr4-tester-footprints:KEMET_D" (layer "F.Cu")
    (at 166.7 104.4 -90)
    (descr "Capacitor SMD KEMET_D")
    (tags "capacitor SMD KEMET_D")
    (property "Author" "Antmicro")
    (property "Dielectric" "")
    (property "License" "Apache-2.0")
    (property "MPN" "T520D337M006ATE045")
    (property "Manufacturer" "KEMET")
    (property "Sheetfile" "fpga-power.kicad_sch")
    (property "Sheetname" "FPGA power")
    (property "Val" "330u")
    (property "Voltage" "")
    (property "ki_description" " ")
    (attr smd)
    (fp_text reference "C8" (at 3.785 -3.07 -90) (layer "F.SilkS")
        (effects (font (size 0.7 0.7) (thickness 0.15)) (justify left bottom))
    )
    (fp_text value "C_330u_KEMET_D" (at 0 3.6 -90) (layer "F.Fab") hide
        (effects (font (size 0.7 0.7) (thickness 0.15)) (justify left bottom))
    )
    (fp_text user "License: Apache-2.0" (at -4.5 6.6 -90) (layer "F.Fab") hide
        (effects (font (size 0.7 0.7) (thickness 0.15)) (justify left bottom))
    )
    (fp_text user "Author: Antmicro" (at -4.5 7.6 -90) (layer "F.Fab") hide
        (effects (font (size 0.7 0.7) (thickness 0.15)) (justify left bottom))
    )
    (fp_text user "${REFERENCE}" (at -4.5 5.6 -90) (layer "F.Fab") hide
        (effects (font (size 0.7 0.7) (thickness 0.15)) (justify left bottom))
    )
    (fp_line (start -4.2 -1.55) (end -3.8 -1.55)
      (stroke (width 0.12) (type solid)) (layer "F.SilkS"))
    (fp_line (start -4 -1.75) (end -4 -1.35)
      (stroke (width 0.12) (type solid)) (layer "F.SilkS"))
    (fp_line (start -3.65 -2.15) (end 3.65 -2.15)
      (stroke (width 0.15) (type solid)) (layer "F.SilkS"))
    (fp_line (start -3.65 -1.6) (end -3.65 -2.15)
      (stroke (width 0.15) (type solid)) (layer "F.SilkS"))
    (fp_line (start -3.65 1.6) (end -3.65 2.15)
      (stroke (width 0.15) (type solid)) (layer "F.SilkS"))
    (fp_line (start -3.65 2.15) (end 3.65 2.15)
      (stroke (width 0.15) (type solid)) (layer "F.SilkS"))
    (fp_line (start 3.65 -2.15) (end 3.65 -1.6)
      (stroke (width 0.15) (type solid)) (layer "F.SilkS"))
    (fp_line (start 3.65 2.15) (end 3.65 1.6)
      (stroke (width 0.15) (type solid)) (layer "F.SilkS"))
    (fp_line (start -4.3 1.5) (end -4.3 -1.5)
      (stroke (width 0.05) (type solid)) (layer "F.CrtYd"))
    (fp_line (start -3.8 -2.4) (end -3.8 -1.5)
      (stroke (width 0.05) (type solid)) (layer "F.CrtYd"))
    (fp_line (start -3.8 -2.4) (end 3.8 -2.4)
      (stroke (width 0.05) (type solid)) (layer "F.CrtYd"))
    (fp_line (start -3.8 -1.5) (end -4.3 -1.5)
      (stroke (width 0.05) (type solid)) (layer "F.CrtYd"))
    (fp_line (start -3.8 1.5) (end -4.3 1.5)
      (stroke (width 0.05) (type solid)) (layer "F.CrtYd"))
    (fp_line (start -3.8 2.4) (end -3.8 1.5)
      (stroke (width 0.05) (type solid)) (layer "F.CrtYd"))
    (fp_line (start 3.8 -2.4) (end 3.8 -1.5)
      (stroke (width 0.05) (type solid)) (layer "F.CrtYd"))
    (fp_line (start 3.8 -1.5) (end 4.3 -1.5)
      (stroke (width 0.05) (type solid)) (layer "F.CrtYd"))
    (fp_line (start 3.8 1.5) (end 3.8 2.4)
      (stroke (width 0.05) (type solid)) (layer "F.CrtYd"))
    (fp_line (start 3.8 2.4) (end -3.8 2.4)
      (stroke (width 0.05) (type solid)) (layer "F.CrtYd"))
    (fp_line (start 4.3 -1.5) (end 4.3 1.5)
      (stroke (width 0.05) (type solid)) (layer "F.CrtYd"))
    (fp_line (start 4.3 1.5) (end 3.8 1.5)
      (stroke (width 0.05) (type solid)) (layer "F.CrtYd"))
    (fp_rect (start -3.65 -2.15) (end 3.65 2.15)
      (stroke (width 0.15) (type solid)) (fill none) (layer "F.Fab"))
    (pad "1" smd rect (at -3.1 0 270) (size 2.31 2.52) (layers "F.Cu" "F.Paste" "F.Mask")
      (net 147 "1V0_SYS") (pintype "passive"))
    (pad "2" smd rect (at 3.1 0 270) (size 2.31 2.52) (layers "F.Cu" "F.Paste" "F.Mask")
      (net 9 "GND") (pintype "passive"))
  )
	(footprint "data-center-rdimm-ddr4-tester-footprints:C_0603_1608Metric" (layer "F.Cu")
    (at 115.786328 82.060008 180)
    (descr "Capacitor SMD 0603")
    (tags "capacitor 0603")
    (property "Author" "Antmicro")
    (property "Dielectric" "")
    (property "License" "Apache-2.0")
    (property "MPN" "06031C103JAT2A")
    (property "Manufacturer" "AVX")
    (property "Sheetfile" "supply.kicad_sch")
    (property "Sheetname" "Supply")
    (property "Val" "10n")
    (property "Voltage" "")
    (property "ki_description" " ")
    (attr smd)
    (fp_text reference "C107" (at 1.446328 10.230008 180) (layer "F.SilkS")
        (effects (font (size 0.7 0.7) (thickness 0.15)) (justify left bottom))
    )
    (fp_text value "C_10n_0603" (at 0 1.6 180) (layer "F.Fab") hide
        (effects (font (size 0.7 0.7) (thickness 0.15)) (justify left bottom))
    )
    (fp_text user "Author: Antmicro" (at -1.682 4.894 180) (layer "F.Fab") hide
        (effects (font (size 0.7 0.7) (thickness 0.15)) (justify left bottom))
    )
    (fp_text user "License: Apache-2.0" (at -1.682 5.895 180) (layer "F.Fab") hide
        (effects (font (size 0.7 0.7) (thickness 0.15)) (justify left bottom))
    )
    (fp_text user "${REFERENCE}" (at -1.682 3.895 180) (layer "F.Fab") hide
        (effects (font (size 0.7 0.7) (thickness 0.15)) (justify left bottom))
    )
    (fp_line (start -0.3 -0.3) (end 0.3 -0.3)
      (stroke (width 0.15) (type solid)) (layer "F.SilkS"))
    (fp_line (start -0.3 0.3) (end 0.3 0.3)
      (stroke (width 0.15) (type solid)) (layer "F.SilkS"))
    (fp_rect (start -1.24 -0.7) (end 1.24 0.7)
      (stroke (width 0.05) (type solid)) (fill none) (layer "F.CrtYd"))
    (fp_rect (start -0.8 -0.4) (end 0.8 0.4)
      (stroke (width 0.15) (type solid)) (fill none) (layer "F.Fab"))
    (pad "1" smd roundrect (at -0.7 0 180) (size 0.6 0.8) (layers "F.Cu" "F.Paste" "F.Mask") (roundrect_rratio 0.2)
      (net 77 "VDDQ") (pintype "passive"))
    (pad "2" smd roundrect (at 0.7 0 180) (size 0.6 0.8) (layers "F.Cu" "F.Paste" "F.Mask") (roundrect_rratio 0.2)
      (net 9 "GND") (pintype "passive"))
  )
	(footprint "data-center-rdimm-ddr4-tester-footprints:C_0603_1608Metric" (layer "F.Cu")
    (at 155.803 75.756)
    (descr "Capacitor SMD 0603")
    (tags "capacitor 0603")
    (property "Author" "Antmicro")
    (property "Dielectric" "")
    (property "License" "Apache-2.0")
    (property "MPN" "GRM188R60J476ME15D")
    (property "Manufacturer" "Murata")
    (property "Sheetfile" "hyperram.kicad_sch")
    (property "Sheetname" "HyperRAM")
    (property "Val" "47u")
    (property "Voltage" "")
    (property "ki_description" " ")
    (attr smd)
    (fp_text reference "C102" (at -1.313 -0.826) (layer "F.SilkS")
        (effects (font (size 0.7 0.7) (thickness 0.15)) (justify left bottom))
    )
    (fp_text value "C_47u_0603" (at 0 1.6) (layer "F.Fab") hide
        (effects (font (size 0.7 0.7) (thickness 0.15)) (justify left bottom))
    )
    (fp_text user "Author: Antmicro" (at -1.682 4.894) (layer "F.Fab") hide
        (effects (font (size 0.7 0.7) (thickness 0.15)) (justify left bottom))
    )
    (fp_text user "${REFERENCE}" (at -1.682 3.895) (layer "F.Fab") hide
        (effects (font (size 0.7 0.7) (thickness 0.15)) (justify left bottom))
    )
    (fp_text user "License: Apache-2.0" (at -1.682 5.895) (layer "F.Fab") hide
        (effects (font (size 0.7 0.7) (thickness 0.15)) (justify left bottom))
    )
    (fp_line (start -0.3 -0.3) (end 0.3 -0.3)
      (stroke (width 0.15) (type solid)) (layer "F.SilkS"))
    (fp_line (start -0.3 0.3) (end 0.3 0.3)
      (stroke (width 0.15) (type solid)) (layer "F.SilkS"))
    (fp_rect (start -1.24 -0.7) (end 1.24 0.7)
      (stroke (width 0.05) (type solid)) (fill none) (layer "F.CrtYd"))
    (fp_rect (start -0.8 -0.4) (end 0.8 0.4)
      (stroke (width 0.15) (type solid)) (fill none) (layer "F.Fab"))
    (pad "1" smd roundrect (at -0.7 0) (size 0.6 0.8) (layers "F.Cu" "F.Paste" "F.Mask") (roundrect_rratio 0.2)
      (net 143 "3V3_SYS") (pintype "passive"))
    (pad "2" smd roundrect (at 0.7 0) (size 0.6 0.8) (layers "F.Cu" "F.Paste" "F.Mask") (roundrect_rratio 0.2)
      (net 9 "GND") (pintype "passive"))
  )
	(footprint "data-center-rdimm-ddr4-tester-footprints:R_0402_1005Metric" (layer "F.Cu")
    (at 152.6026 75.502 -90)
    (descr "Resistor SMD 0402")
    (tags "resistor SMD 0402")
    (property "Author" "Antmicro")
    (property "License" "Apache-2.0")
    (property "MPN" "CR0402-FX-1002GLF")
    (property "Manufacturer" "Bourns")
    (property "Sheetfile" "hyperram.kicad_sch")
    (property "Sheetname" "HyperRAM")
    (property "Tolerance" "1%")
    (property "Val" "10k")
    (property "ki_description" "10k resistor in 0402 package with 1% tolerance")
    (attr smd)
    (fp_text reference "R61" (at -0.832 -0.3574 -90) (layer "F.SilkS")
        (effects (font (size 0.7 0.7) (thickness 0.15)) (justify left bottom))
    )
    (fp_text value "R_10k_0402" (at 0 1.4 -90) (layer "F.Fab") hide
        (effects (font (size 0.7 0.7) (thickness 0.15)) (justify left bottom))
    )
    (fp_text user "Author: Antmicro" (at -0.95 4.169 -90) (layer "F.Fab") hide
        (effects (font (size 0.7 0.7) (thickness 0.15)) (justify left bottom))
    )
    (fp_text user "${REFERENCE}" (at -0.95 3.168 -90) (layer "F.Fab") hide
        (effects (font (size 0.7 0.7) (thickness 0.15)) (justify left bottom))
    )
    (fp_text user "License: Apache-2.0" (at -0.95 5.169 -90) (layer "F.Fab") hide
        (effects (font (size 0.7 0.7) (thickness 0.15)) (justify left bottom))
    )
    (fp_rect (start -0.93 -0.47) (end 0.93 0.47)
      (stroke (width 0.05) (type solid)) (fill none) (layer "F.CrtYd"))
    (fp_rect (start -0.5 -0.25) (end 0.5 0.25)
      (stroke (width 0.15) (type solid)) (fill none) (layer "F.Fab"))
    (pad "1" smd roundrect (at -0.485 0 270) (size 0.59 0.64) (layers "F.Cu" "F.Paste" "F.Mask") (roundrect_rratio 0.25)
      (net 143 "3V3_SYS") (pintype "passive"))
    (pad "2" smd roundrect (at 0.485 0 270) (size 0.59 0.64) (layers "F.Cu" "F.Paste" "F.Mask") (roundrect_rratio 0.25)
      (net 155 "HR_CS") (pintype "passive"))
  )
)
